(kicad_pcb
	(version 20260206)
	(generator "pcbnew")
	(generator_version "10.0")
	(general
		(thickness 1.6)
		(legacy_teardrops no)
	)
	(paper "A4")
	(title_block
		(title "v1-chassis-manager — T6M_CM_d_v01_1031_1645.brd")
		(comment 1 "Open CloudServer (Microsoft) / footprints 1895-1904 of 2512")
	)
	(layers
		(0 "F.Cu" signal "TOP")
		(4 "In1.Cu" signal "GND1")
		(6 "In2.Cu" signal "IN1")
		(8 "In3.Cu" signal "VCC1")
		(10 "In4.Cu" signal "VCC2")
		(12 "In5.Cu" signal "GND2")
		(14 "In6.Cu" signal "IN2")
		(16 "In7.Cu" signal "IN3")
		(18 "In8.Cu" signal "GND3")
		(2 "B.Cu" signal "BOTTOM")
		(9 "F.Adhes" user "F.Adhesive")
		(11 "B.Adhes" user "B.Adhesive")
		(13 "F.Paste" user "Package Geometry/Pastemask Top")
		(15 "B.Paste" user "Package Geometry/Pastemask Bottom")
		(5 "F.SilkS" user "Ref Des/Silkscreen Top")
		(7 "B.SilkS" user "Ref Des/Silkscreen Bottom")
		(1 "F.Mask" user "Board Geometry/Soldermask Top")
		(3 "B.Mask" user "Board Geometry/Soldermask Bottom")
		(17 "Dwgs.User" user "User.Drawings")
		(19 "Cmts.User" user "User.Comments")
		(21 "Eco1.User" user "User.Eco1")
		(23 "Eco2.User" user "User.Eco2")
		(25 "Edge.Cuts" user "Board Geometry/Outline")
		(27 "Margin" user)
		(31 "F.CrtYd" user "Package Geometry/Place Bound Top")
		(29 "B.CrtYd" user "Package Geometry/Place Bound Bottom")
		(35 "F.Fab" user "Ref Des/Assembly Top")
		(33 "B.Fab" user "Ref Des/Assembly Bottom")
	)
	(footprint ""
		(layer "B.Cu")
		(at 80.272128 -77.946504)
		(property "Reference" "R118"
			(at 4.055872 0.292862 0)
			(unlocked yes)
			(layer "B.SilkS")
			(effects
				(font
					(size 0.7874 0.5842)
					(thickness 0.1524)
				)
				(justify left mirror)
			)
		)
		(property "Value" ""
			(at 0 0 0)
			(layer "B.Fab")
			(effects
				(font
					(size 1.27 1.27)
				)
				(justify mirror)
			)
		)
		(duplicate_pad_numbers_are_jumpers no)
		(fp_line
			(start -0.7874 -0.4064)
			(end -0.7874 0.4064)
			(stroke
				(width 0.1524)
				(type default)
			)
			(layer "B.SilkS")
		)
		(fp_line
			(start -0.7874 0.4064)
			(end 0.7874 0.4064)
			(stroke
				(width 0.1524)
				(type default)
			)
			(layer "B.SilkS")
		)
		(fp_line
			(start 0.7874 -0.4064)
			(end -0.7874 -0.4064)
			(stroke
				(width 0.1524)
				(type default)
			)
			(layer "B.SilkS")
		)
		(fp_line
			(start 0.7874 0.4064)
			(end 0.7874 -0.4064)
			(stroke
				(width 0.1524)
				(type default)
			)
			(layer "B.SilkS")
		)
		(fp_poly
			(pts
				(xy 0.508 0.2794) (xy 0.508 0.2286) (xy 0.635 0.2286) (xy 0.635 -0.254) (xy 0.5334 -0.254) (xy 0.5334 -0.2794)
				(xy -0.5334 -0.2794) (xy -0.5334 -0.254) (xy -0.635 -0.254) (xy -0.635 0.254) (xy -0.5334 0.254)
				(xy -0.5334 0.2794)
			)
			(stroke
				(width 0)
				(type default)
			)
			(fill no)
			(layer "B.CrtYd")
		)
		(pad "1" smd rect
			(at -0.40005 0 180)
			(size 0.4572 0.508)
			(layers "B.Cu" "B.Mask" "B.Paste")
			(net "SVID_CPU_NODE1_PVCCP_ALERT_R_L")
		)
		(pad "2" smd rect
			(at 0.40005 0 180)
			(size 0.4572 0.508)
			(layers "B.Cu" "B.Mask" "B.Paste")
			(net "SVID_CPU_NODE1_PVCCP_ALERT_L")
		)
	)
	(footprint ""
		(layer "B.Cu")
		(at 165.210998 -152.84323 180)
		(property "Reference" "C453"
			(at 1.075182 -0.208534 0)
			(unlocked yes)
			(layer "B.SilkS")
			(effects
				(font
					(size 0.7874 0.5842)
					(thickness 0.1524)
				)
				(justify left mirror)
			)
		)
		(property "Value" ""
			(at 0 0 0)
			(layer "B.Fab")
			(effects
				(font
					(size 1.27 1.27)
				)
				(justify mirror)
			)
		)
		(duplicate_pad_numbers_are_jumpers no)
		(fp_line
			(start 0.7874 0.4064)
			(end 0.7874 -0.4064)
			(stroke
				(width 0.1524)
				(type default)
			)
			(layer "B.SilkS")
		)
		(fp_line
			(start 0.7874 -0.4064)
			(end -0.7874 -0.4064)
			(stroke
				(width 0.1524)
				(type default)
			)
			(layer "B.SilkS")
		)
		(fp_line
			(start 0 0.381)
			(end 0 -0.381)
			(stroke
				(width 0.1524)
				(type default)
			)
			(layer "B.SilkS")
		)
		(fp_line
			(start -0.7874 0.4064)
			(end 0.7874 0.4064)
			(stroke
				(width 0.1524)
				(type default)
			)
			(layer "B.SilkS")
		)
		(fp_line
			(start -0.7874 -0.4064)
			(end -0.7874 0.4064)
			(stroke
				(width 0.1524)
				(type default)
			)
			(layer "B.SilkS")
		)
		(fp_poly
			(pts
				(xy 0.5334 0.254) (xy 0.635 0.254) (xy 0.635 0.2286) (xy 0.635 -0.254) (xy 0.5334 -0.254) (xy 0.5334 -0.2794)
				(xy -0.5334 -0.2794) (xy -0.5334 -0.254) (xy -0.635 -0.254) (xy -0.635 0.254) (xy -0.5334 0.254)
				(xy -0.5334 0.2794) (xy 0.508 0.2794) (xy 0.5334 0.2794)
			)
			(stroke
				(width 0)
				(type default)
			)
			(fill no)
			(layer "B.CrtYd")
		)
		(pad "1" smd rect
			(at -0.40005 0)
			(size 0.4572 0.508)
			(layers "B.Cu" "B.Mask" "B.Paste")
			(net "P1V9_LAN2")
		)
		(pad "2" smd rect
			(at 0.40005 0)
			(size 0.4572 0.508)
			(layers "B.Cu" "B.Mask" "B.Paste")
			(net "GND")
		)
	)
	(footprint ""
		(layer "B.Cu")
		(at 122.0978 -41.684702)
		(property "Reference" "R185"
			(at -2.808732 0.279146 0)
			(unlocked yes)
			(layer "B.SilkS")
			(effects
				(font
					(size 0.7874 0.5842)
					(thickness 0.1524)
				)
				(justify left mirror)
			)
		)
		(property "Value" ""
			(at 0 0 0)
			(layer "B.Fab")
			(effects
				(font
					(size 1.27 1.27)
				)
				(justify mirror)
			)
		)
		(duplicate_pad_numbers_are_jumpers no)
		(fp_line
			(start -0.7874 -0.406146)
			(end -0.7874 0.406146)
			(stroke
				(width 0.1524)
				(type default)
			)
			(layer "B.SilkS")
		)
		(fp_line
			(start -0.7874 0.406146)
			(end 0.7874 0.406146)
			(stroke
				(width 0.1524)
				(type default)
			)
			(layer "B.SilkS")
		)
		(fp_line
			(start 0.7874 -0.406146)
			(end -0.7874 -0.406146)
			(stroke
				(width 0.1524)
				(type default)
			)
			(layer "B.SilkS")
		)
		(fp_line
			(start 0.7874 0.406146)
			(end 0.7874 -0.406146)
			(stroke
				(width 0.1524)
				(type default)
			)
			(layer "B.SilkS")
		)
		(fp_poly
			(pts
				(xy 0.508 0.2794) (xy 0.508 0.2286) (xy 0.635 0.2286) (xy 0.635 -0.254) (xy 0.5334 -0.254) (xy 0.5334 -0.2794)
				(xy -0.5334 -0.2794) (xy -0.5334 -0.254) (xy -0.635 -0.254) (xy -0.635 0.254) (xy -0.5334 0.254)
				(xy -0.5334 0.2794)
			)
			(stroke
				(width 0)
				(type default)
			)
			(fill no)
			(layer "B.CrtYd")
		)
		(pad "1" smd rect
			(at -0.40005 0 180)
			(size 0.4572 0.508)
			(layers "B.Cu" "B.Mask" "B.Paste")
			(net "LPC_CPU_NODE1_LAD3")
		)
		(pad "2" smd rect
			(at 0.40005 0 180)
			(size 0.4572 0.508)
			(layers "B.Cu" "B.Mask" "B.Paste")
			(net "LPC_CPU_NODE1_LAD3_SIO")
		)
	)
	(footprint ""
		(layer "B.Cu")
		(at 77.07376 -188.126624 -90)
		(property "Reference" "C652"
			(at -4.151884 0.22098 270)
			(unlocked yes)
			(layer "B.SilkS")
			(effects
				(font
					(size 0.7874 0.5842)
					(thickness 0.1524)
				)
				(justify left mirror)
			)
		)
		(property "Value" ""
			(at 0 0 90)
			(layer "B.Fab")
			(effects
				(font
					(size 1.27 1.27)
				)
				(justify mirror)
			)
		)
		(duplicate_pad_numbers_are_jumpers no)
		(fp_line
			(start -0.7874 0.4064)
			(end 0.7874 0.4064)
			(stroke
				(width 0.1524)
				(type default)
			)
			(layer "B.SilkS")
		)
		(fp_line
			(start 0.7874 0.4064)
			(end 0.7874 -0.4064)
			(stroke
				(width 0.1524)
				(type default)
			)
			(layer "B.SilkS")
		)
		(fp_line
			(start 0 0.381)
			(end 0 -0.381)
			(stroke
				(width 0.1524)
				(type default)
			)
			(layer "B.SilkS")
		)
		(fp_line
			(start -0.7874 -0.4064)
			(end -0.7874 0.4064)
			(stroke
				(width 0.1524)
				(type default)
			)
			(layer "B.SilkS")
		)
		(fp_line
			(start 0.7874 -0.4064)
			(end -0.7874 -0.4064)
			(stroke
				(width 0.1524)
				(type default)
			)
			(layer "B.SilkS")
		)
		(fp_poly
			(pts
				(xy 0.5334 0.254) (xy 0.635 0.254) (xy 0.635 0.2286) (xy 0.635 -0.254) (xy 0.5334 -0.254) (xy 0.5334 -0.2794)
				(xy -0.5334 -0.2794) (xy -0.5334 -0.254) (xy -0.635 -0.254) (xy -0.635 0.254) (xy -0.5334 0.254)
				(xy -0.5334 0.2794) (xy 0.508 0.2794) (xy 0.5334 0.2794)
			)
			(stroke
				(width 0)
				(type default)
			)
			(fill no)
			(layer "B.CrtYd")
		)
		(pad "1" smd rect
			(at -0.40005 0 90)
			(size 0.4572 0.508)
			(layers "B.Cu" "B.Mask" "B.Paste")
			(net "T3_NODE3_EN_R")
		)
		(pad "2" smd rect
			(at 0.40005 0 90)
			(size 0.4572 0.508)
			(layers "B.Cu" "B.Mask" "B.Paste")
			(net "GND")
		)
	)
	(footprint ""
		(layer "B.Cu")
		(at 159.801814 -49.607978)
		(property "Reference" "C494"
			(at 1.435608 -2.73304 0)
			(unlocked yes)
			(layer "B.SilkS")
			(effects
				(font
					(size 0.7874 0.5842)
					(thickness 0.1524)
				)
				(justify left mirror)
			)
		)
		(property "Value" ""
			(at 0 0 0)
			(layer "B.Fab")
			(effects
				(font
					(size 1.27 1.27)
				)
				(justify mirror)
			)
		)
		(duplicate_pad_numbers_are_jumpers no)
		(fp_line
			(start -0.7874 -0.4064)
			(end -0.7874 0.4064)
			(stroke
				(width 0.1524)
				(type default)
			)
			(layer "B.SilkS")
		)
		(fp_line
			(start -0.7874 0.4064)
			(end 0.7874 0.4064)
			(stroke
				(width 0.1524)
				(type default)
			)
			(layer "B.SilkS")
		)
		(fp_line
			(start 0 0.381)
			(end 0 -0.381)
			(stroke
				(width 0.1524)
				(type default)
			)
			(layer "B.SilkS")
		)
		(fp_line
			(start 0.7874 -0.4064)
			(end -0.7874 -0.4064)
			(stroke
				(width 0.1524)
				(type default)
			)
			(layer "B.SilkS")
		)
		(fp_line
			(start 0.7874 0.4064)
			(end 0.7874 -0.4064)
			(stroke
				(width 0.1524)
				(type default)
			)
			(layer "B.SilkS")
		)
		(fp_poly
			(pts
				(xy 0.5334 0.254) (xy 0.635 0.254) (xy 0.635 0.2286) (xy 0.635 -0.254) (xy 0.5334 -0.254) (xy 0.5334 -0.2794)
				(xy -0.5334 -0.2794) (xy -0.5334 -0.254) (xy -0.635 -0.254) (xy -0.635 0.254) (xy -0.5334 0.254)
				(xy -0.5334 0.2794) (xy 0.508 0.2794) (xy 0.5334 0.2794)
			)
			(stroke
				(width 0)
				(type default)
			)
			(fill no)
			(layer "B.CrtYd")
		)
		(pad "1" smd rect
			(at -0.40005 0 180)
			(size 0.4572 0.508)
			(layers "B.Cu" "B.Mask" "B.Paste")
			(net "SATA_RX0_C_DN")
		)
		(pad "2" smd rect
			(at 0.40005 0 180)
			(size 0.4572 0.508)
			(layers "B.Cu" "B.Mask" "B.Paste")
			(net "SATA_A_NODE1_RX_N0")
		)
	)
	(footprint ""
		(layer "B.Cu")
		(at 135.196834 -35.343084)
		(property "Reference" "R1183"
			(at -5.415788 18.464784 0)
			(unlocked yes)
			(layer "B.SilkS")
			(effects
				(font
					(size 0.7874 0.5842)
					(thickness 0.1524)
				)
				(justify left mirror)
			)
		)
		(property "Value" ""
			(at 0 0 0)
			(layer "B.Fab")
			(effects
				(font
					(size 1.27 1.27)
				)
				(justify mirror)
			)
		)
		(duplicate_pad_numbers_are_jumpers no)
		(fp_line
			(start -0.7874 -0.4064)
			(end -0.7874 0.4064)
			(stroke
				(width 0.1524)
				(type default)
			)
			(layer "B.SilkS")
		)
		(fp_line
			(start -0.7874 0.4064)
			(end 0.7874 0.4064)
			(stroke
				(width 0.1524)
				(type default)
			)
			(layer "B.SilkS")
		)
		(fp_line
			(start 0.7874 -0.4064)
			(end -0.7874 -0.4064)
			(stroke
				(width 0.1524)
				(type default)
			)
			(layer "B.SilkS")
		)
		(fp_line
			(start 0.7874 0.4064)
			(end 0.7874 -0.4064)
			(stroke
				(width 0.1524)
				(type default)
			)
			(layer "B.SilkS")
		)
		(fp_poly
			(pts
				(xy 0.508 0.2794) (xy 0.508 0.2286) (xy 0.635 0.2286) (xy 0.635 -0.254) (xy 0.5334 -0.254) (xy 0.5334 -0.2794)
				(xy -0.5334 -0.2794) (xy -0.5334 -0.254) (xy -0.635 -0.254) (xy -0.635 0.254) (xy -0.5334 0.254)
				(xy -0.5334 0.2794)
			)
			(stroke
				(width 0)
				(type default)
			)
			(fill no)
			(layer "B.CrtYd")
		)
		(pad "1" smd rect
			(at -0.40005 0 180)
			(size 0.4572 0.508)
			(layers "B.Cu" "B.Mask" "B.Paste")
			(net "CPLD123_RSV2")
		)
		(pad "2" smd rect
			(at 0.40005 0 180)
			(size 0.4572 0.508)
			(layers "B.Cu" "B.Mask" "B.Paste")
			(net "SIO_CPLD_RSV2_R")
		)
	)
	(footprint ""
		(layer "B.Cu")
		(at 65.721992 -129.79146 -90)
		(property "Reference" "R328"
			(at 56.331866 41.181274 270)
			(unlocked yes)
			(layer "B.SilkS")
			(effects
				(font
					(size 0.7874 0.5842)
					(thickness 0.1524)
				)
				(justify left mirror)
			)
		)
		(property "Value" ""
			(at 0 0 90)
			(layer "B.Fab")
			(effects
				(font
					(size 1.27 1.27)
				)
				(justify mirror)
			)
		)
		(duplicate_pad_numbers_are_jumpers no)
		(fp_line
			(start -0.7874 0.4064)
			(end 0.7874 0.4064)
			(stroke
				(width 0.1524)
				(type default)
			)
			(layer "B.SilkS")
		)
		(fp_line
			(start 0.7874 0.4064)
			(end 0.7874 -0.4064)
			(stroke
				(width 0.1524)
				(type default)
			)
			(layer "B.SilkS")
		)
		(fp_line
			(start -0.7874 -0.4064)
			(end -0.7874 0.4064)
			(stroke
				(width 0.1524)
				(type default)
			)
			(layer "B.SilkS")
		)
		(fp_line
			(start 0.7874 -0.4064)
			(end -0.7874 -0.4064)
			(stroke
				(width 0.1524)
				(type default)
			)
			(layer "B.SilkS")
		)
		(fp_poly
			(pts
				(xy 0.508 0.2794) (xy 0.508 0.2286) (xy 0.635 0.2286) (xy 0.635 -0.254) (xy 0.5334 -0.254) (xy 0.5334 -0.2794)
				(xy -0.5334 -0.2794) (xy -0.5334 -0.254) (xy -0.635 -0.254) (xy -0.635 0.254) (xy -0.5334 0.254)
				(xy -0.5334 0.2794)
			)
			(stroke
				(width 0)
				(type default)
			)
			(fill no)
			(layer "B.CrtYd")
		)
		(pad "1" smd rect
			(at -0.40005 0 90)
			(size 0.4572 0.508)
			(layers "B.Cu" "B.Mask" "B.Paste")
			(net "P3V3_NODE1")
		)
		(pad "2" smd rect
			(at 0.40005 0 90)
			(size 0.4572 0.508)
			(layers "B.Cu" "B.Mask" "B.Paste")
			(net "BMC_ROMA12")
		)
	)
	(footprint ""
		(layer "B.Cu")
		(at 138.79576 -184.951624 90)
		(property "Reference" "R864"
			(at 4.357624 -2.004568 270)
			(unlocked yes)
			(layer "B.SilkS")
			(effects
				(font
					(size 0.7874 0.5842)
					(thickness 0.1524)
				)
				(justify left mirror)
			)
		)
		(property "Value" ""
			(at 0 0 90)
			(layer "B.Fab")
			(effects
				(font
					(size 1.27 1.27)
				)
				(justify mirror)
			)
		)
		(duplicate_pad_numbers_are_jumpers no)
		(fp_line
			(start 0.7874 -0.4064)
			(end -0.7874 -0.4064)
			(stroke
				(width 0.1524)
				(type default)
			)
			(layer "B.SilkS")
		)
		(fp_line
			(start -0.7874 -0.4064)
			(end -0.7874 0.4064)
			(stroke
				(width 0.1524)
				(type default)
			)
			(layer "B.SilkS")
		)
		(fp_line
			(start 0.7874 0.4064)
			(end 0.7874 -0.4064)
			(stroke
				(width 0.1524)
				(type default)
			)
			(layer "B.SilkS")
		)
		(fp_line
			(start -0.7874 0.4064)
			(end 0.7874 0.4064)
			(stroke
				(width 0.1524)
				(type default)
			)
			(layer "B.SilkS")
		)
		(fp_poly
			(pts
				(xy 0.508 0.2794) (xy 0.508 0.2286) (xy 0.635 0.2286) (xy 0.635 -0.254) (xy 0.5334 -0.254) (xy 0.5334 -0.2794)
				(xy -0.5334 -0.2794) (xy -0.5334 -0.254) (xy -0.635 -0.254) (xy -0.635 0.254) (xy -0.5334 0.254)
				(xy -0.5334 0.2794)
			)
			(stroke
				(width 0)
				(type default)
			)
			(fill no)
			(layer "B.CrtYd")
		)
		(pad "1" smd rect
			(at -0.40005 0 270)
			(size 0.4572 0.508)
			(layers "B.Cu" "B.Mask" "B.Paste")
			(net "T9_NODE2_EN")
		)
		(pad "2" smd rect
			(at 0.40005 0 270)
			(size 0.4572 0.508)
			(layers "B.Cu" "B.Mask" "B.Paste")
			(net "T9_NODE2_EN_R")
		)
	)
	(footprint ""
		(layer "B.Cu")
		(at 77.63256 -185.259218 90)
		(property "Reference" "R889"
			(at 3.766566 0.076454 270)
			(unlocked yes)
			(layer "B.SilkS")
			(effects
				(font
					(size 0.7874 0.5842)
					(thickness 0.1524)
				)
				(justify left mirror)
			)
		)
		(property "Value" ""
			(at 0 0 90)
			(layer "B.Fab")
			(effects
				(font
					(size 1.27 1.27)
				)
				(justify mirror)
			)
		)
		(duplicate_pad_numbers_are_jumpers no)
		(fp_line
			(start 0.7874 -0.4064)
			(end -0.7874 -0.4064)
			(stroke
				(width 0.1524)
				(type default)
			)
			(layer "B.SilkS")
		)
		(fp_line
			(start -0.7874 -0.4064)
			(end -0.7874 0.4064)
			(stroke
				(width 0.1524)
				(type default)
			)
			(layer "B.SilkS")
		)
		(fp_line
			(start 0.7874 0.4064)
			(end 0.7874 -0.4064)
			(stroke
				(width 0.1524)
				(type default)
			)
			(layer "B.SilkS")
		)
		(fp_line
			(start -0.7874 0.4064)
			(end 0.7874 0.4064)
			(stroke
				(width 0.1524)
				(type default)
			)
			(layer "B.SilkS")
		)
		(fp_poly
			(pts
				(xy 0.508 0.2794) (xy 0.508 0.2286) (xy 0.635 0.2286) (xy 0.635 -0.254) (xy 0.5334 -0.254) (xy 0.5334 -0.2794)
				(xy -0.5334 -0.2794) (xy -0.5334 -0.254) (xy -0.635 -0.254) (xy -0.635 0.254) (xy -0.5334 0.254)
				(xy -0.5334 0.2794)
			)
			(stroke
				(width 0)
				(type default)
			)
			(fill no)
			(layer "B.CrtYd")
		)
		(pad "1" smd rect
			(at -0.40005 0 270)
			(size 0.4572 0.508)
			(layers "B.Cu" "B.Mask" "B.Paste")
			(net "T3_NODE3_EN")
		)
		(pad "2" smd rect
			(at 0.40005 0 270)
			(size 0.4572 0.508)
			(layers "B.Cu" "B.Mask" "B.Paste")
			(net "T3_NODE3_EN_R")
		)
	)
	(footprint ""
		(layer "B.Cu")
		(at 105.191814 -104.85882)
		(property "Reference" "PC116"
			(at -3.119374 -0.397002 0)
			(unlocked yes)
			(layer "B.SilkS")
			(effects
				(font
					(size 0.7874 0.5842)
					(thickness 0.1524)
				)
				(justify left mirror)
			)
		)
		(property "Value" ""
			(at 0 0 0)
			(layer "B.Fab")
			(effects
				(font
					(size 1.27 1.27)
				)
				(justify mirror)
			)
		)
		(duplicate_pad_numbers_are_jumpers no)
		(fp_line
			(start -1.905 -0.8636)
			(end -1.905 0.8636)
			(stroke
				(width 0.1524)
				(type default)
			)
			(layer "B.SilkS")
		)
		(fp_line
			(start -1.905 0.8636)
			(end 1.905 0.8636)
			(stroke
				(width 0.1524)
				(type default)
			)
			(layer "B.SilkS")
		)
		(fp_line
			(start 0 0.8382)
			(end 0 -0.8382)
			(stroke
				(width 0.1524)
				(type default)
			)
			(layer "B.SilkS")
		)
		(fp_line
			(start 1.905 -0.8636)
			(end -1.905 -0.8636)
			(stroke
				(width 0.1524)
				(type default)
			)
			(layer "B.SilkS")
		)
		(fp_line
			(start 1.905 0.8636)
			(end 1.905 -0.8636)
			(stroke
				(width 0.1524)
				(type default)
			)
			(layer "B.SilkS")
		)
		(fp_rect
			(start 1.524 0.7366)
			(end -1.524 -0.7366)
			(stroke
				(width 0)
				(type default)
			)
			(fill no)
			(layer "B.CrtYd")
		)
		(pad "1" smd rect
			(at -0.94996 0 180)
			(size 1.1176 1.3716)
			(layers "B.Cu" "B.Mask" "B.Paste")
			(net "GND")
		)
		(pad "2" smd rect
			(at 0.94996 0 180)
			(size 1.1176 1.3716)
			(layers "B.Cu" "B.Mask" "B.Paste")
			(net "PV_VCCP_NODE1")
		)
	)
)
